# TIMECARD (Time Appliance Project (Time Card)) — schematic netlist excerpt (pin names and nets, part order shuffled) for the footprints in the layout excerpt that follows; sources: Cadence DE-HDL packaged netlist, KiCad conversion of R4006-B0001-02_R01.brd

R63  RESISTOR  4.7KOHM 1%  pkg SMC_0402R_H016  page 9 : \1\ = XP3R3V_FPGA ; \2\ = PCIE_PERST_N

(kicad_pcb
	(version 20260206)
	(generator "pcbnew")
	(generator_version "10.0")
	(general
		(thickness 1.6)
		(legacy_teardrops no)
	)
	(paper "A4")
	(title_block
		(title "timecard-production-celestica-r4006 — R4006-B0001-02_R01.brd")
		(comment 1 "Time Appliance Project (Time Card) / footprints 173-173 of 1113")
	)
	(layers
		(0 "F.Cu" signal "TOP")
		(4 "In1.Cu" signal "L02_GND1")
		(6 "In2.Cu" signal "L03_SIG1")
		(8 "In3.Cu" signal "L04_GND2")
		(10 "In4.Cu" signal "L05_VCC1")
		(12 "In5.Cu" signal "L06_VCC2")
		(14 "In6.Cu" signal "L07_GND3")
		(16 "In7.Cu" signal "L08_SIG2")
		(18 "In8.Cu" signal "L09_GND4")
		(2 "B.Cu" signal "BOTTOM")
		(9 "F.Adhes" user "F.Adhesive")
		(11 "B.Adhes" user "B.Adhesive")
		(13 "F.Paste" user "Package Geometry/Pastemask Top")
		(15 "B.Paste" user "Package Geometry/Pastemask Bottom")
		(5 "F.SilkS" user "Ref Des/Silkscreen Top")
		(7 "B.SilkS" user "Ref Des/Silkscreen Bottom")
		(1 "F.Mask" user "Board Geometry/Soldermask Top")
		(3 "B.Mask" user "Board Geometry/Soldermask Bottom")
		(17 "Dwgs.User" user "User.Drawings")
		(19 "Cmts.User" user "User.Comments")
		(21 "Eco1.User" user "User.Eco1")
		(23 "Eco2.User" user "User.Eco2")
		(25 "Edge.Cuts" user "Board Geometry/Outline")
		(27 "Margin" user)
		(31 "F.CrtYd" user "Package Geometry/Place Bound Top")
		(29 "B.CrtYd" user "Package Geometry/Place Bound Bottom")
		(35 "F.Fab" user "Ref Des/Assembly Top")
		(33 "B.Fab" user "Ref Des/Assembly Bottom")
	)
	(footprint ""
		(layer "F.Cu")
		(at 75.5904 -15.7734)
		(property "Reference" "R63"
			(at 0.3556 -2.98323 0)
			(unlocked yes)
			(layer "F.SilkS")
			(effects
				(font
					(size 0.7874 0.5842)
					(thickness 0.1524)
				)
			)
		)
		(property "Value" "VAL*"
			(at 0.02032 2.13233 0)
			(unlocked yes)
			(layer "F.Fab")
			(hide yes)
			(effects
				(font
					(size 0.7874 0.5842)
					(thickness 0.1524)
				)
			)
		)
		(property "Tolerance" "TOL*"
			(at 0.044704 3.05435 0)
			(unlocked yes)
			(layer "Cmts.User")
			(hide yes)
			(effects
				(font
					(size 0.7874 0.5842)
					(thickness 0.1524)
				)
			)
		)
		(property "User Part Number" "PARTNUM*"
			(at 0.02032 4.024884 0)
			(unlocked yes)
			(layer "Cmts.User")
			(hide yes)
			(effects
				(font
					(size 0.7874 0.5842)
					(thickness 0.1524)
				)
			)
		)
		(property "Device Type" "RESISTOR-G155-14701-01,4.7KOHMA"
			(at 0.008382 1.210564 0)
			(unlocked yes)
			(layer "F.Fab")
			(hide yes)
			(effects
				(font
					(size 0.7874 0.5842)
					(thickness 0.1524)
				)
			)
		)
		(duplicate_pad_numbers_are_jumpers no)
		(fp_line
			(start -1.143 -0.5588)
			(end -1.143 0.5588)
			(stroke
				(width 0.1)
				(type default)
			)
			(layer "F.SilkS")
		)
		(fp_line
			(start -1.143 0.5588)
			(end 1.143 0.5588)
			(stroke
				(width 0.1)
				(type default)
			)
			(layer "F.SilkS")
		)
		(fp_line
			(start 1.143 -0.5588)
			(end -1.143 -0.5588)
			(stroke
				(width 0.1)
				(type default)
			)
			(layer "F.SilkS")
		)
		(fp_line
			(start 1.143 0.5588)
			(end 1.143 -0.5588)
			(stroke
				(width 0.1)
				(type default)
			)
			(layer "F.SilkS")
		)
		(fp_poly
			(pts
				(xy -1.143 0.5588) (xy 1.143 0.5588) (xy 1.143 -0.5588) (xy -1.143 -0.5588)
			)
			(stroke
				(width 0)
				(type default)
			)
			(fill no)
			(layer "F.CrtYd")
		)
		(fp_line
			(start -0.508 -0.3048)
			(end -0.508 0.3048)
			(stroke
				(width 0.1)
				(type default)
			)
			(layer "F.Fab")
		)
		(fp_line
			(start -0.508 0.3048)
			(end 0.508 0.3048)
			(stroke
				(width 0.1)
				(type default)
			)
			(layer "F.Fab")
		)
		(fp_line
			(start 0.508 -0.3048)
			(end -0.508 -0.3048)
			(stroke
				(width 0.1)
				(type default)
			)
			(layer "F.Fab")
		)
		(fp_line
			(start 0.508 0.3048)
			(end 0.508 -0.3048)
			(stroke
				(width 0.1)
				(type default)
			)
			(layer "F.Fab")
		)
		(pad "1" smd rect
			(at -0.5334 0)
			(size 0.7112 0.6096)
			(layers "F.Cu" "F.Mask" "F.Paste")
			(net "XP3R3V_FPGA")
		)
		(pad "2" smd rect
			(at 0.5334 0)
			(size 0.7112 0.6096)
			(layers "F.Cu" "F.Mask" "F.Paste")
			(net "PCIE_PERST_N")
		)
		(zone
			(layer "F.Cu")
			(hatch none 0.5)
			(connect_pads
				(clearance 0)
			)
			(min_thickness 0.25)
			(keepout
				(tracks not_allowed)
				(vias allowed)
				(pads allowed)
				(copperpour not_allowed)
				(footprints allowed)
			)
			(placement
				(enabled no)
				(sheetname "")
			)
			(fill
				(thermal_gap 0.5)
				(thermal_bridge_width 0.5)
				(island_removal_mode 0)
			)
			(polygon
				(pts
					(xy 75.5142 -15.4686) (xy 75.6666 -15.4686) (xy 75.6666 -16.0782) (xy 75.5142 -16.0782)
				)
			)
		)
		(zone
			(layer "F.Cu")
			(hatch none 0.5)
			(connect_pads
				(clearance 0)
			)
			(min_thickness 0.25)
			(keepout
				(tracks allowed)
				(vias not_allowed)
				(pads allowed)
				(copperpour not_allowed)
				(footprints allowed)
			)
			(placement
				(enabled no)
				(sheetname "")
			)
			(fill
				(thermal_gap 0.5)
				(thermal_bridge_width 0.5)
				(island_removal_mode 0)
			)
			(polygon
				(pts
					(xy 75.5142 -15.4686) (xy 75.6666 -15.4686) (xy 75.6666 -16.0782) (xy 75.5142 -16.0782)
				)
			)
		)
	)
)
